(kicad_pcb
	(version 20260206)
	(generator "pcbnew")
	(generator_version "10.0")
	(general
		(thickness 1.6)
		(legacy_teardrops no)
	)
	(paper "A4")
	(title_block
		(title "v1-chassis-manager — T6M_CM_d_v01_1031_1645.brd")
		(comment 1 "Open CloudServer (Microsoft) / footprints 1010-1018 of 2512")
	)
	(layers
		(0 "F.Cu" signal "TOP")
		(4 "In1.Cu" signal "GND1")
		(6 "In2.Cu" signal "IN1")
		(8 "In3.Cu" signal "VCC1")
		(10 "In4.Cu" signal "VCC2")
		(12 "In5.Cu" signal "GND2")
		(14 "In6.Cu" signal "IN2")
		(16 "In7.Cu" signal "IN3")
		(18 "In8.Cu" signal "GND3")
		(2 "B.Cu" signal "BOTTOM")
		(9 "F.Adhes" user "F.Adhesive")
		(11 "B.Adhes" user "B.Adhesive")
		(13 "F.Paste" user "Package Geometry/Pastemask Top")
		(15 "B.Paste" user "Package Geometry/Pastemask Bottom")
		(5 "F.SilkS" user "Ref Des/Silkscreen Top")
		(7 "B.SilkS" user "Ref Des/Silkscreen Bottom")
		(1 "F.Mask" user "Board Geometry/Soldermask Top")
		(3 "B.Mask" user "Board Geometry/Soldermask Bottom")
		(17 "Dwgs.User" user "User.Drawings")
		(19 "Cmts.User" user "User.Comments")
		(21 "Eco1.User" user "User.Eco1")
		(23 "Eco2.User" user "User.Eco2")
		(25 "Edge.Cuts" user "Board Geometry/Outline")
		(27 "Margin" user)
		(31 "F.CrtYd" user "Package Geometry/Place Bound Top")
		(29 "B.CrtYd" user "Package Geometry/Place Bound Bottom")
		(35 "F.Fab" user "Ref Des/Assembly Top")
		(33 "B.Fab" user "Ref Des/Assembly Bottom")
	)
	(footprint ""
		(layer "F.Cu")
		(at 82.614516 -104.569768 -90)
		(property "Reference" "Q32"
			(at 0.106426 -2.088896 90)
			(unlocked yes)
			(layer "F.SilkS")
			(effects
				(font
					(size 0.7874 0.5842)
					(thickness 0.1524)
				)
			)
		)
		(property "Value" ""
			(at 0 0 270)
			(layer "F.Fab")
			(effects
				(font
					(size 1.27 1.27)
				)
			)
		)
		(duplicate_pad_numbers_are_jumpers no)
		(fp_line
			(start -1.603248 1.500124)
			(end -1.603248 -1.500124)
			(stroke
				(width 0.1524)
				(type default)
			)
			(layer "F.SilkS")
		)
		(fp_line
			(start 1.603248 1.500124)
			(end -1.603248 1.500124)
			(stroke
				(width 0.1524)
				(type default)
			)
			(layer "F.SilkS")
		)
		(fp_line
			(start -1.603248 -1.500124)
			(end 1.603248 -1.500124)
			(stroke
				(width 0.1524)
				(type default)
			)
			(layer "F.SilkS")
		)
		(fp_line
			(start 1.603248 -1.500124)
			(end 1.603248 1.500124)
			(stroke
				(width 0.1524)
				(type default)
			)
			(layer "F.SilkS")
		)
		(fp_poly
			(pts
				(xy -0.700024 -1.500124) (xy -0.700024 -1.40716) (xy -1.507998 -1.40716) (xy -1.507998 -0.49276)
				(xy -0.700024 -0.49276) (xy -0.700024 0.47244) (xy -1.507998 0.47244) (xy -1.507998 1.41224) (xy -0.700024 1.41224)
				(xy -0.700024 1.500124) (xy 0.700024 1.500124) (xy 0.700024 0.47244) (xy 1.514602 0.47244) (xy 1.514602 -0.46736)
				(xy 0.700024 -0.46736) (xy 0.700024 -1.500124)
			)
			(stroke
				(width 0)
				(type default)
			)
			(fill no)
			(layer "F.CrtYd")
		)
		(fp_line
			(start -0.700024 1.500124)
			(end -0.700024 -1.500124)
			(stroke
				(width 0.1)
				(type default)
			)
			(layer "F.Fab")
		)
		(fp_line
			(start 0.700024 1.500124)
			(end -0.700024 1.500124)
			(stroke
				(width 0.1)
				(type default)
			)
			(layer "F.Fab")
		)
		(fp_line
			(start -0.700024 -1.500124)
			(end 0.700024 -1.500124)
			(stroke
				(width 0.1)
				(type default)
			)
			(layer "F.Fab")
		)
		(fp_line
			(start 0.700024 -1.500124)
			(end 0.700024 1.500124)
			(stroke
				(width 0.1)
				(type default)
			)
			(layer "F.Fab")
		)
		(fp_text user "S"
			(at -0.713486 1.863598 0)
			(unlocked yes)
			(layer "F.SilkS")
			(effects
				(font
					(size 0.635 0.4064)
					(thickness 0.1524)
				)
			)
		)
		(fp_text user "D"
			(at -2.051812 1.655826 0)
			(unlocked yes)
			(layer "F.SilkS")
			(effects
				(font
					(size 0.635 0.4064)
					(thickness 0.1524)
				)
			)
		)
		(fp_text user "G"
			(at 1.781556 -2.125218 0)
			(unlocked yes)
			(layer "F.SilkS")
			(effects
				(font
					(size 0.635 0.4064)
					(thickness 0.1524)
				)
			)
		)
		(fp_text user "S"
			(at -1.025906 2.0066 180)
			(unlocked yes)
			(layer "F.Fab")
			(effects
				(font
					(size 0.7874 0.5842)
					(thickness 0.000001)
				)
			)
		)
		(fp_text user "D"
			(at 2.098294 0.1016 180)
			(unlocked yes)
			(layer "F.Fab")
			(effects
				(font
					(size 0.7874 0.5842)
					(thickness 0.000001)
				)
			)
		)
		(fp_text user "G"
			(at -1.051306 -2.032 180)
			(unlocked yes)
			(layer "F.Fab")
			(effects
				(font
					(size 0.7874 0.5842)
					(thickness 0.000001)
				)
			)
		)
		(pad "D" smd rect
			(at 0.999998 0 180)
			(size 0.8128 0.9144)
			(layers "F.Cu" "F.Mask" "F.Paste")
			(net "FM_CPLD_NODE1_P3V3_SUS_EN_LV")
		)
		(pad "G" smd rect
			(at -0.999998 -0.94996 180)
			(size 0.8128 0.9144)
			(layers "F.Cu" "F.Mask" "F.Paste")
			(net "FM_CPLD_NODE1_P3V3_SUS_EN_G")
		)
		(pad "S" smd rect
			(at -0.999998 0.94996 180)
			(size 0.8128 0.9144)
			(layers "F.Cu" "F.Mask" "F.Paste")
			(net "FM_CPLD_NODE1_P3V3_SUS_EN")
		)
	)
	(footprint ""
		(layer "F.Cu")
		(at 94.211394 -185.790586)
		(property "Reference" "C678"
			(at -1.182878 -7.228586 0)
			(unlocked yes)
			(layer "F.SilkS")
			(effects
				(font
					(size 0.7874 0.5842)
					(thickness 0.1524)
				)
				(justify left)
			)
		)
		(property "Value" ""
			(at 0 0 0)
			(layer "F.Fab")
			(effects
				(font
					(size 1.27 1.27)
				)
			)
		)
		(duplicate_pad_numbers_are_jumpers no)
		(fp_line
			(start -0.7874 -0.4064)
			(end 0.7874 -0.4064)
			(stroke
				(width 0.1524)
				(type default)
			)
			(layer "F.SilkS")
		)
		(fp_line
			(start -0.7874 0.4064)
			(end -0.7874 -0.4064)
			(stroke
				(width 0.1524)
				(type default)
			)
			(layer "F.SilkS")
		)
		(fp_line
			(start 0 0.381)
			(end 0 -0.381)
			(stroke
				(width 0.1524)
				(type default)
			)
			(layer "F.SilkS")
		)
		(fp_line
			(start 0.7874 -0.4064)
			(end 0.7874 0.4064)
			(stroke
				(width 0.1524)
				(type default)
			)
			(layer "F.SilkS")
		)
		(fp_line
			(start 0.7874 0.4064)
			(end -0.7874 0.4064)
			(stroke
				(width 0.1524)
				(type default)
			)
			(layer "F.SilkS")
		)
		(fp_poly
			(pts
				(xy -0.5334 0.254) (xy -0.635 0.254) (xy -0.635 0.2286) (xy -0.635 -0.254) (xy -0.5334 -0.254) (xy -0.5334 -0.2794)
				(xy 0.5334 -0.2794) (xy 0.5334 -0.254) (xy 0.635 -0.254) (xy 0.635 0.254) (xy 0.5334 0.254) (xy 0.5334 0.2794)
				(xy -0.508 0.2794) (xy -0.5334 0.2794)
			)
			(stroke
				(width 0)
				(type default)
			)
			(fill no)
			(layer "F.CrtYd")
		)
		(pad "1" smd rect
			(at 0.40005 0)
			(size 0.4572 0.508)
			(layers "F.Cu" "F.Mask" "F.Paste")
			(net "UART_T5_NODE2_RXD")
		)
		(pad "2" smd rect
			(at -0.40005 0)
			(size 0.4572 0.508)
			(layers "F.Cu" "F.Mask" "F.Paste")
			(net "GND")
		)
	)
	(footprint ""
		(layer "F.Cu")
		(at 49.38776 -185.205624 90)
		(property "Reference" "R839"
			(at 4.006088 0.055372 90)
			(unlocked yes)
			(layer "F.SilkS")
			(effects
				(font
					(size 0.7874 0.5842)
					(thickness 0.1524)
				)
				(justify left)
			)
		)
		(property "Value" ""
			(at 0 0 90)
			(layer "F.Fab")
			(effects
				(font
					(size 1.27 1.27)
				)
			)
		)
		(duplicate_pad_numbers_are_jumpers no)
		(fp_line
			(start 0.7874 -0.4064)
			(end 0.7874 0.4064)
			(stroke
				(width 0.1524)
				(type default)
			)
			(layer "F.SilkS")
		)
		(fp_line
			(start -0.7874 -0.4064)
			(end 0.7874 -0.4064)
			(stroke
				(width 0.1524)
				(type default)
			)
			(layer "F.SilkS")
		)
		(fp_line
			(start 0.7874 0.4064)
			(end -0.7874 0.4064)
			(stroke
				(width 0.1524)
				(type default)
			)
			(layer "F.SilkS")
		)
		(fp_line
			(start -0.7874 0.4064)
			(end -0.7874 -0.4064)
			(stroke
				(width 0.1524)
				(type default)
			)
			(layer "F.SilkS")
		)
		(fp_poly
			(pts
				(xy -0.508 0.2794) (xy -0.508 0.2286) (xy -0.635 0.2286) (xy -0.635 -0.254) (xy -0.5334 -0.254)
				(xy -0.5334 -0.2794) (xy 0.5334 -0.2794) (xy 0.5334 -0.254) (xy 0.635 -0.254) (xy 0.635 0.254) (xy 0.5334 0.254)
				(xy 0.5334 0.2794)
			)
			(stroke
				(width 0)
				(type default)
			)
			(fill no)
			(layer "F.CrtYd")
		)
		(pad "1" smd rect
			(at 0.40005 0 90)
			(size 0.4572 0.508)
			(layers "F.Cu" "F.Mask" "F.Paste")
			(net "PSU4_AC_OK_R")
		)
		(pad "2" smd rect
			(at -0.40005 0 90)
			(size 0.4572 0.508)
			(layers "F.Cu" "F.Mask" "F.Paste")
			(net "PSU4_AC_OK")
		)
	)
	(footprint ""
		(layer "F.Cu")
		(at 116.398548 -138.065002)
		(property "Reference" "PC103"
			(at 2.059432 -4.505706 0)
			(unlocked yes)
			(layer "F.SilkS")
			(effects
				(font
					(size 0.7874 0.5842)
					(thickness 0.1524)
				)
				(justify left)
			)
		)
		(property "Value" ""
			(at 0 0 0)
			(layer "F.Fab")
			(effects
				(font
					(size 1.27 1.27)
				)
			)
		)
		(duplicate_pad_numbers_are_jumpers no)
		(fp_line
			(start -0.7874 -0.4064)
			(end 0.7874 -0.4064)
			(stroke
				(width 0.1524)
				(type default)
			)
			(layer "F.SilkS")
		)
		(fp_line
			(start -0.7874 0.4064)
			(end -0.7874 -0.4064)
			(stroke
				(width 0.1524)
				(type default)
			)
			(layer "F.SilkS")
		)
		(fp_line
			(start 0 0.381)
			(end 0 -0.381)
			(stroke
				(width 0.1524)
				(type default)
			)
			(layer "F.SilkS")
		)
		(fp_line
			(start 0.7874 -0.4064)
			(end 0.7874 0.4064)
			(stroke
				(width 0.1524)
				(type default)
			)
			(layer "F.SilkS")
		)
		(fp_line
			(start 0.7874 0.4064)
			(end -0.7874 0.4064)
			(stroke
				(width 0.1524)
				(type default)
			)
			(layer "F.SilkS")
		)
		(fp_poly
			(pts
				(xy -0.5334 0.254) (xy -0.635 0.254) (xy -0.635 0.2286) (xy -0.635 -0.254) (xy -0.5334 -0.254) (xy -0.5334 -0.2794)
				(xy 0.5334 -0.2794) (xy 0.5334 -0.254) (xy 0.635 -0.254) (xy 0.635 0.254) (xy 0.5334 0.254) (xy 0.5334 0.2794)
				(xy -0.508 0.2794) (xy -0.5334 0.2794)
			)
			(stroke
				(width 0)
				(type default)
			)
			(fill no)
			(layer "F.CrtYd")
		)
		(pad "1" smd rect
			(at 0.40005 0)
			(size 0.4572 0.508)
			(layers "F.Cu" "F.Mask" "F.Paste")
			(net "VR_PVCCP_NODE1_FB_RC")
		)
		(pad "2" smd rect
			(at -0.40005 0)
			(size 0.4572 0.508)
			(layers "F.Cu" "F.Mask" "F.Paste")
			(net "VR_PVCCP_NODE1_VSEN")
		)
	)
	(footprint ""
		(layer "F.Cu")
		(at 25.391872 -94.661228 90)
		(property "Reference" "C537"
			(at -1.12776 2.645664 90)
			(unlocked yes)
			(layer "F.SilkS")
			(effects
				(font
					(size 0.7874 0.5842)
					(thickness 0.1524)
				)
				(justify left)
			)
		)
		(property "Value" ""
			(at 0 0 90)
			(layer "F.Fab")
			(effects
				(font
					(size 1.27 1.27)
				)
			)
		)
		(duplicate_pad_numbers_are_jumpers no)
		(fp_line
			(start 0.7874 -0.4064)
			(end 0.7874 0.4064)
			(stroke
				(width 0.1524)
				(type default)
			)
			(layer "F.SilkS")
		)
		(fp_line
			(start -0.7874 -0.4064)
			(end 0.7874 -0.4064)
			(stroke
				(width 0.1524)
				(type default)
			)
			(layer "F.SilkS")
		)
		(fp_line
			(start 0 0.381)
			(end 0 -0.381)
			(stroke
				(width 0.1524)
				(type default)
			)
			(layer "F.SilkS")
		)
		(fp_line
			(start 0.7874 0.4064)
			(end -0.7874 0.4064)
			(stroke
				(width 0.1524)
				(type default)
			)
			(layer "F.SilkS")
		)
		(fp_line
			(start -0.7874 0.4064)
			(end -0.7874 -0.4064)
			(stroke
				(width 0.1524)
				(type default)
			)
			(layer "F.SilkS")
		)
		(fp_poly
			(pts
				(xy -0.5334 0.254) (xy -0.635 0.254) (xy -0.635 0.2286) (xy -0.635 -0.254) (xy -0.5334 -0.254) (xy -0.5334 -0.2794)
				(xy 0.5334 -0.2794) (xy 0.5334 -0.254) (xy 0.635 -0.254) (xy 0.635 0.254) (xy 0.5334 0.254) (xy 0.5334 0.2794)
				(xy -0.508 0.2794) (xy -0.5334 0.2794)
			)
			(stroke
				(width 0)
				(type default)
			)
			(fill no)
			(layer "F.CrtYd")
		)
		(pad "1" smd rect
			(at 0.40005 0 90)
			(size 0.4572 0.508)
			(layers "F.Cu" "F.Mask" "F.Paste")
			(net "P3V3_NODE1")
		)
		(pad "2" smd rect
			(at -0.40005 0 90)
			(size 0.4572 0.508)
			(layers "F.Cu" "F.Mask" "F.Paste")
			(net "GND")
		)
	)
	(footprint ""
		(layer "F.Cu")
		(at 142.478252 -26.320242 90)
		(property "Reference" "C483"
			(at -9.766808 3.98653 90)
			(unlocked yes)
			(layer "F.SilkS")
			(effects
				(font
					(size 0.7874 0.5842)
					(thickness 0.1524)
				)
			)
		)
		(property "Value" ""
			(at 0 0 90)
			(layer "F.Fab")
			(effects
				(font
					(size 1.27 1.27)
				)
			)
		)
		(duplicate_pad_numbers_are_jumpers no)
		(fp_line
			(start 1.2954 -0.5842)
			(end 1.2954 0.5842)
			(stroke
				(width 0.1524)
				(type default)
			)
			(layer "F.SilkS")
		)
		(fp_line
			(start 0 -0.5842)
			(end 0 0.5842)
			(stroke
				(width 0.1524)
				(type default)
			)
			(layer "F.SilkS")
		)
		(fp_line
			(start -1.2954 -0.5842)
			(end 1.2954 -0.5842)
			(stroke
				(width 0.1524)
				(type default)
			)
			(layer "F.SilkS")
		)
		(fp_line
			(start 1.2954 0.5842)
			(end -1.2954 0.5842)
			(stroke
				(width 0.1524)
				(type default)
			)
			(layer "F.SilkS")
		)
		(fp_line
			(start -1.2954 0.5842)
			(end -1.2954 -0.5842)
			(stroke
				(width 0.1524)
				(type default)
			)
			(layer "F.SilkS")
		)
		(fp_poly
			(pts
				(xy 0.8636 -0.4572) (xy 0.8636 -0.3556) (xy 1.143 -0.3556) (xy 1.143 0.3556) (xy 0.8636 0.3556)
				(xy 0.8636 0.4572) (xy -0.8636 0.4572) (xy -0.8636 0.3556) (xy -1.143 0.3556) (xy -1.143 -0.3556)
				(xy -0.8636 -0.3556) (xy -0.8636 -0.4572)
			)
			(stroke
				(width 0)
				(type default)
			)
			(fill no)
			(layer "F.CrtYd")
		)
		(fp_line
			(start 0.884936 -0.504952)
			(end 0.884936 0.504952)
			(stroke
				(width 0.1)
				(type default)
			)
			(layer "F.Fab")
		)
		(fp_line
			(start -0.884936 -0.504952)
			(end 0.884936 -0.504952)
			(stroke
				(width 0.1)
				(type default)
			)
			(layer "F.Fab")
		)
		(fp_line
			(start 0.884936 0.504952)
			(end -0.884936 0.504952)
			(stroke
				(width 0.1)
				(type default)
			)
			(layer "F.Fab")
		)
		(fp_line
			(start -0.884936 0.504952)
			(end -0.884936 -0.504952)
			(stroke
				(width 0.1)
				(type default)
			)
			(layer "F.Fab")
		)
		(pad "1" smd rect
			(at 0.7366 0 180)
			(size 0.7112 0.8128)
			(layers "F.Cu" "F.Mask" "F.Paste")
			(net "SIO_AVCC")
		)
		(pad "2" smd rect
			(at -0.7366 0 180)
			(size 0.7112 0.8128)
			(layers "F.Cu" "F.Mask" "F.Paste")
			(net "GNDA")
		)
	)
	(footprint ""
		(layer "F.Cu")
		(at 15.298166 -29.250132)
		(property "Reference" "C547"
			(at -1.003046 1.467104 0)
			(unlocked yes)
			(layer "F.SilkS")
			(effects
				(font
					(size 0.7874 0.5842)
					(thickness 0.1524)
				)
				(justify left)
			)
		)
		(property "Value" ""
			(at 0 0 0)
			(layer "F.Fab")
			(effects
				(font
					(size 1.27 1.27)
				)
			)
		)
		(duplicate_pad_numbers_are_jumpers no)
		(fp_line
			(start -0.7874 -0.4064)
			(end 0.7874 -0.4064)
			(stroke
				(width 0.1524)
				(type default)
			)
			(layer "F.SilkS")
		)
		(fp_line
			(start -0.7874 0.4064)
			(end -0.7874 -0.4064)
			(stroke
				(width 0.1524)
				(type default)
			)
			(layer "F.SilkS")
		)
		(fp_line
			(start 0 0.381)
			(end 0 -0.381)
			(stroke
				(width 0.1524)
				(type default)
			)
			(layer "F.SilkS")
		)
		(fp_line
			(start 0.7874 -0.4064)
			(end 0.7874 0.4064)
			(stroke
				(width 0.1524)
				(type default)
			)
			(layer "F.SilkS")
		)
		(fp_line
			(start 0.7874 0.4064)
			(end -0.7874 0.4064)
			(stroke
				(width 0.1524)
				(type default)
			)
			(layer "F.SilkS")
		)
		(fp_poly
			(pts
				(xy -0.5334 0.254) (xy -0.635 0.254) (xy -0.635 0.2286) (xy -0.635 -0.254) (xy -0.5334 -0.254) (xy -0.5334 -0.2794)
				(xy 0.5334 -0.2794) (xy 0.5334 -0.254) (xy 0.635 -0.254) (xy 0.635 0.254) (xy 0.5334 0.254) (xy 0.5334 0.2794)
				(xy -0.508 0.2794) (xy -0.5334 0.2794)
			)
			(stroke
				(width 0)
				(type default)
			)
			(fill no)
			(layer "F.CrtYd")
		)
		(pad "1" smd rect
			(at 0.40005 0)
			(size 0.4572 0.508)
			(layers "F.Cu" "F.Mask" "F.Paste")
			(net "N54251527")
		)
		(pad "2" smd rect
			(at -0.40005 0)
			(size 0.4572 0.508)
			(layers "F.Cu" "F.Mask" "F.Paste")
			(net "N54251529")
		)
	)
	(footprint ""
		(layer "F.Cu")
		(at 83.98256 -80.683608 -90)
		(property "Reference" "C90"
			(at 17.592294 -1.189482 90)
			(unlocked yes)
			(layer "F.SilkS")
			(effects
				(font
					(size 0.7874 0.5842)
					(thickness 0.1524)
				)
				(justify left)
			)
		)
		(property "Value" ""
			(at 0 0 270)
			(layer "F.Fab")
			(effects
				(font
					(size 1.27 1.27)
				)
			)
		)
		(duplicate_pad_numbers_are_jumpers no)
		(fp_line
			(start -0.7874 0.4064)
			(end -0.7874 -0.4064)
			(stroke
				(width 0.1524)
				(type default)
			)
			(layer "F.SilkS")
		)
		(fp_line
			(start 0.7874 0.4064)
			(end -0.7874 0.4064)
			(stroke
				(width 0.1524)
				(type default)
			)
			(layer "F.SilkS")
		)
		(fp_line
			(start 0 0.381)
			(end 0 -0.381)
			(stroke
				(width 0.1524)
				(type default)
			)
			(layer "F.SilkS")
		)
		(fp_line
			(start -0.7874 -0.4064)
			(end 0.7874 -0.4064)
			(stroke
				(width 0.1524)
				(type default)
			)
			(layer "F.SilkS")
		)
		(fp_line
			(start 0.7874 -0.4064)
			(end 0.7874 0.4064)
			(stroke
				(width 0.1524)
				(type default)
			)
			(layer "F.SilkS")
		)
		(fp_poly
			(pts
				(xy -0.5334 0.254) (xy -0.635 0.254) (xy -0.635 0.2286) (xy -0.635 -0.254) (xy -0.5334 -0.254) (xy -0.5334 -0.2794)
				(xy 0.5334 -0.2794) (xy 0.5334 -0.254) (xy 0.635 -0.254) (xy 0.635 0.254) (xy 0.5334 0.254) (xy 0.5334 0.2794)
				(xy -0.508 0.2794) (xy -0.5334 0.2794)
			)
			(stroke
				(width 0)
				(type default)
			)
			(fill no)
			(layer "F.CrtYd")
		)
		(pad "1" smd rect
			(at 0.40005 0 270)
			(size 0.4572 0.508)
			(layers "F.Cu" "F.Mask" "F.Paste")
			(net "PV_VCCP_NODE1")
		)
		(pad "2" smd rect
			(at -0.40005 0 270)
			(size 0.4572 0.508)
			(layers "F.Cu" "F.Mask" "F.Paste")
			(net "GND")
		)
	)
	(footprint ""
		(layer "F.Cu")
		(at 60.071508 -111.743744 180)
		(property "Reference" "PC18"
			(at 1.989582 -7.189978 0)
			(unlocked yes)
			(layer "F.SilkS")
			(effects
				(font
					(size 0.7874 0.5842)
					(thickness 0.1524)
				)
				(justify left)
			)
		)
		(property "Value" ""
			(at 0 0 180)
			(layer "F.Fab")
			(effects
				(font
					(size 1.27 1.27)
				)
			)
		)
		(duplicate_pad_numbers_are_jumpers no)
		(fp_line
			(start 0.7874 0.4064)
			(end -0.7874 0.4064)
			(stroke
				(width 0.1524)
				(type default)
			)
			(layer "F.SilkS")
		)
		(fp_line
			(start 0.7874 -0.4064)
			(end 0.7874 0.4064)
			(stroke
				(width 0.1524)
				(type default)
			)
			(layer "F.SilkS")
		)
		(fp_line
			(start 0 0.381)
			(end 0 -0.381)
			(stroke
				(width 0.1524)
				(type default)
			)
			(layer "F.SilkS")
		)
		(fp_line
			(start -0.7874 0.4064)
			(end -0.7874 -0.4064)
			(stroke
				(width 0.1524)
				(type default)
			)
			(layer "F.SilkS")
		)
		(fp_line
			(start -0.7874 -0.4064)
			(end 0.7874 -0.4064)
			(stroke
				(width 0.1524)
				(type default)
			)
			(layer "F.SilkS")
		)
		(fp_poly
			(pts
				(xy -0.5334 0.254) (xy -0.635 0.254) (xy -0.635 0.2286) (xy -0.635 -0.254) (xy -0.5334 -0.254) (xy -0.5334 -0.2794)
				(xy 0.5334 -0.2794) (xy 0.5334 -0.254) (xy 0.635 -0.254) (xy 0.635 0.254) (xy 0.5334 0.254) (xy 0.5334 0.2794)
				(xy -0.508 0.2794) (xy -0.5334 0.2794)
			)
			(stroke
				(width 0)
				(type default)
			)
			(fill no)
			(layer "F.CrtYd")
		)
		(pad "1" smd rect
			(at 0.40005 0 180)
			(size 0.4572 0.508)
			(layers "F.Cu" "F.Mask" "F.Paste")
			(net "P3V3_STB_NODE1")
		)
		(pad "2" smd rect
			(at -0.40005 0 180)
			(size 0.4572 0.508)
			(layers "F.Cu" "F.Mask" "F.Paste")
			(net "GND")
		)
	)
)
